# SCM (Grand Teton) — schematic netlist excerpt (pin names and nets, part order shuffled) for the footprints in the layout excerpt that follows; sources: Cadence DE-HDL packaged netlist, KiCad conversion of 12092022_DA0F0TMDCD0_F0T_Management_Board_D_brd_V3_OCP.brd

C111  Q_CAP  1UF 25V 10% X6S  pkg C0402  page 16 : A = P1V8_AUX ; B = GND
C8  Q_CAP  0.1UF 25V 10% X7R  pkg 0402  page 20 : A = P2V5_AUX ; B = GND

(kicad_pcb
	(version 20260206)
	(generator "pcbnew")
	(generator_version "10.0")
	(general
		(thickness 1.6)
		(legacy_teardrops no)
	)
	(paper "A4")
	(title_block
		(title "12092022_DA0F0TMDCD0_F0T_Management_Board_D_brd_V3_OCP.brd")
		(comment 1 "Grand Teton / footprints 749-750 of 1440")
	)
	(layers
		(0 "F.Cu" signal "TOP")
		(4 "In1.Cu" signal "GND")
		(6 "In2.Cu" signal "IN1")
		(8 "In3.Cu" signal "GND1")
		(10 "In4.Cu" signal "IN2")
		(12 "In5.Cu" signal "VCC")
		(14 "In6.Cu" signal "VCC1")
		(16 "In7.Cu" signal "IN3")
		(18 "In8.Cu" signal "GND2")
		(20 "In9.Cu" signal "IN4")
		(22 "In10.Cu" signal "GND3")
		(2 "B.Cu" signal "BOTTOM")
		(9 "F.Adhes" user "F.Adhesive")
		(11 "B.Adhes" user "B.Adhesive")
		(13 "F.Paste" user "Package Geometry/Pastemask Top")
		(15 "B.Paste" user "Package Geometry/Pastemask Bottom")
		(5 "F.SilkS" user "Ref Des/Silkscreen Top")
		(7 "B.SilkS" user "Ref Des/Silkscreen Bottom")
		(1 "F.Mask" user "Board Geometry/Soldermask Top")
		(3 "B.Mask" user "Board Geometry/Soldermask Bottom")
		(17 "Dwgs.User" user "User.Drawings")
		(19 "Cmts.User" user "User.Comments")
		(21 "Eco1.User" user "User.Eco1")
		(23 "Eco2.User" user "User.Eco2")
		(25 "Edge.Cuts" user "Board Geometry/Outline")
		(27 "Margin" user)
		(31 "F.CrtYd" user "Package Geometry/Place Bound Top")
		(29 "B.CrtYd" user "Package Geometry/Place Bound Bottom")
		(35 "F.Fab" user "Ref Des/Assembly Top")
		(33 "B.Fab" user "Ref Des/Assembly Bottom")
	)
	(footprint ""
		(layer "B.Cu")
		(at 54.853332 -50.652934 -90)
		(property "Reference" "C111"
			(at 0 0 90)
			(layer "B.SilkS")
			(hide yes)
			(effects
				(font
					(size 1.27 1.27)
				)
				(justify mirror)
			)
		)
		(property "Value" ""
			(at 0 0 90)
			(layer "B.Fab")
			(effects
				(font
					(size 1.27 1.27)
				)
				(justify mirror)
			)
		)
		(duplicate_pad_numbers_are_jumpers no)
		(fp_line
			(start -0.7874 0.4064)
			(end 0.7874 0.4064)
			(stroke
				(width 0.1524)
				(type default)
			)
			(layer "B.SilkS")
		)
		(fp_line
			(start 0.7874 0.4064)
			(end 0.7874 -0.4064)
			(stroke
				(width 0.1524)
				(type default)
			)
			(layer "B.SilkS")
		)
		(fp_line
			(start -0.7874 -0.4064)
			(end -0.7874 0.4064)
			(stroke
				(width 0.1524)
				(type default)
			)
			(layer "B.SilkS")
		)
		(fp_line
			(start 0.7874 -0.4064)
			(end -0.7874 -0.4064)
			(stroke
				(width 0.1524)
				(type default)
			)
			(layer "B.SilkS")
		)
		(fp_line
			(start -0.67945 0.3048)
			(end -0.120396 0.3048)
			(stroke
				(width 0.1)
				(type default)
			)
			(layer "B.Fab")
		)
		(fp_line
			(start -0.120396 0.3048)
			(end -0.120396 0.2794)
			(stroke
				(width 0.1)
				(type default)
			)
			(layer "B.Fab")
		)
		(fp_line
			(start 0.12065 0.3048)
			(end 0.67945 0.3048)
			(stroke
				(width 0.1)
				(type default)
			)
			(layer "B.Fab")
		)
		(fp_line
			(start 0.67945 0.3048)
			(end 0.67945 -0.305054)
			(stroke
				(width 0.1)
				(type default)
			)
			(layer "B.Fab")
		)
		(fp_line
			(start -0.120396 0.2794)
			(end 0.12065 0.2794)
			(stroke
				(width 0.1)
				(type default)
			)
			(layer "B.Fab")
		)
		(fp_line
			(start 0.12065 0.2794)
			(end 0.12065 0.3048)
			(stroke
				(width 0.1)
				(type default)
			)
			(layer "B.Fab")
		)
		(fp_line
			(start -0.12065 -0.2794)
			(end -0.12065 -0.3048)
			(stroke
				(width 0.1)
				(type default)
			)
			(layer "B.Fab")
		)
		(fp_line
			(start 0.12065 -0.2794)
			(end -0.12065 -0.2794)
			(stroke
				(width 0.1)
				(type default)
			)
			(layer "B.Fab")
		)
		(fp_line
			(start -0.67945 -0.3048)
			(end -0.67945 0.3048)
			(stroke
				(width 0.1)
				(type default)
			)
			(layer "B.Fab")
		)
		(fp_line
			(start -0.12065 -0.3048)
			(end -0.67945 -0.3048)
			(stroke
				(width 0.1)
				(type default)
			)
			(layer "B.Fab")
		)
		(fp_line
			(start 0.12065 -0.305054)
			(end 0.12065 -0.2794)
			(stroke
				(width 0.1)
				(type default)
			)
			(layer "B.Fab")
		)
		(fp_line
			(start 0.67945 -0.305054)
			(end 0.12065 -0.305054)
			(stroke
				(width 0.1)
				(type default)
			)
			(layer "B.Fab")
		)
		(pad "1" smd circle
			(at 0.40005 0 90)
			(size 0 0)
			(layers "B.Cu" "B.Mask" "B.Paste")
			(net "P1V8_AUX")
		)
		(pad "2" smd circle
			(at -0.40005 0 90)
			(size 0 0)
			(layers "B.Cu" "B.Mask" "B.Paste")
			(net "GND")
		)
	)
	(footprint ""
		(layer "B.Cu")
		(at 81.129886 -43.022012 180)
		(property "Reference" "C8"
			(at 0 0 0)
			(layer "B.SilkS")
			(hide yes)
			(effects
				(font
					(size 1.27 1.27)
				)
				(justify mirror)
			)
		)
		(property "Value" ""
			(at 0 0 0)
			(layer "B.Fab")
			(effects
				(font
					(size 1.27 1.27)
				)
				(justify mirror)
			)
		)
		(duplicate_pad_numbers_are_jumpers no)
		(fp_line
			(start 0.7874 0.4064)
			(end 0.7874 -0.4064)
			(stroke
				(width 0.1524)
				(type default)
			)
			(layer "B.SilkS")
		)
		(fp_line
			(start 0.7874 -0.4064)
			(end -0.7874 -0.4064)
			(stroke
				(width 0.1524)
				(type default)
			)
			(layer "B.SilkS")
		)
		(fp_line
			(start -0.7874 0.4064)
			(end 0.7874 0.4064)
			(stroke
				(width 0.1524)
				(type default)
			)
			(layer "B.SilkS")
		)
		(fp_line
			(start -0.7874 -0.4064)
			(end -0.7874 0.4064)
			(stroke
				(width 0.1524)
				(type default)
			)
			(layer "B.SilkS")
		)
		(fp_line
			(start 0.67945 0.3048)
			(end 0.67945 -0.305054)
			(stroke
				(width 0.1)
				(type default)
			)
			(layer "B.Fab")
		)
		(fp_line
			(start 0.67945 -0.305054)
			(end 0.12065 -0.305054)
			(stroke
				(width 0.1)
				(type default)
			)
			(layer "B.Fab")
		)
		(fp_line
			(start 0.12065 0.3048)
			(end 0.67945 0.3048)
			(stroke
				(width 0.1)
				(type default)
			)
			(layer "B.Fab")
		)
		(fp_line
			(start 0.12065 0.2794)
			(end 0.12065 0.3048)
			(stroke
				(width 0.1)
				(type default)
			)
			(layer "B.Fab")
		)
		(fp_line
			(start 0.12065 -0.2794)
			(end -0.12065 -0.2794)
			(stroke
				(width 0.1)
				(type default)
			)
			(layer "B.Fab")
		)
		(fp_line
			(start 0.12065 -0.305054)
			(end 0.12065 -0.2794)
			(stroke
				(width 0.1)
				(type default)
			)
			(layer "B.Fab")
		)
		(fp_line
			(start -0.120396 0.3048)
			(end -0.120396 0.2794)
			(stroke
				(width 0.1)
				(type default)
			)
			(layer "B.Fab")
		)
		(fp_line
			(start -0.120396 0.2794)
			(end 0.12065 0.2794)
			(stroke
				(width 0.1)
				(type default)
			)
			(layer "B.Fab")
		)
		(fp_line
			(start -0.12065 -0.2794)
			(end -0.12065 -0.3048)
			(stroke
				(width 0.1)
				(type default)
			)
			(layer "B.Fab")
		)
		(fp_line
			(start -0.12065 -0.3048)
			(end -0.67945 -0.3048)
			(stroke
				(width 0.1)
				(type default)
			)
			(layer "B.Fab")
		)
		(fp_line
			(start -0.67945 0.3048)
			(end -0.120396 0.3048)
			(stroke
				(width 0.1)
				(type default)
			)
			(layer "B.Fab")
		)
		(fp_line
			(start -0.67945 -0.3048)
			(end -0.67945 0.3048)
			(stroke
				(width 0.1)
				(type default)
			)
			(layer "B.Fab")
		)
		(pad "1" smd circle
			(at 0.40005 0)
			(size 0 0)
			(layers "B.Cu" "B.Mask" "B.Paste")
			(net "P2V5_AUX")
		)
		(pad "2" smd circle
			(at -0.40005 0)
			(size 0 0)
			(layers "B.Cu" "B.Mask" "B.Paste")
			(net "GND")
		)
	)
)
